(kicad_pcb
	(version 20260206)
	(generator "pcbnew")
	(generator_version "10.0")
	(general
		(thickness 1.6)
		(legacy_teardrops no)
	)
	(paper "A4")
	(title_block
		(title "timecard-production-celestica-r4006 — R4006-B0001-02_R01.brd")
		(comment 1 "Time Appliance Project (Time Card) / footprints 682-686 of 1113")
	)
	(layers
		(0 "F.Cu" signal "TOP")
		(4 "In1.Cu" signal "L02_GND1")
		(6 "In2.Cu" signal "L03_SIG1")
		(8 "In3.Cu" signal "L04_GND2")
		(10 "In4.Cu" signal "L05_VCC1")
		(12 "In5.Cu" signal "L06_VCC2")
		(14 "In6.Cu" signal "L07_GND3")
		(16 "In7.Cu" signal "L08_SIG2")
		(18 "In8.Cu" signal "L09_GND4")
		(2 "B.Cu" signal "BOTTOM")
		(9 "F.Adhes" user "F.Adhesive")
		(11 "B.Adhes" user "B.Adhesive")
		(13 "F.Paste" user "Package Geometry/Pastemask Top")
		(15 "B.Paste" user "Package Geometry/Pastemask Bottom")
		(5 "F.SilkS" user "Ref Des/Silkscreen Top")
		(7 "B.SilkS" user "Ref Des/Silkscreen Bottom")
		(1 "F.Mask" user "Board Geometry/Soldermask Top")
		(3 "B.Mask" user "Board Geometry/Soldermask Bottom")
		(17 "Dwgs.User" user "User.Drawings")
		(19 "Cmts.User" user "User.Comments")
		(21 "Eco1.User" user "User.Eco1")
		(23 "Eco2.User" user "User.Eco2")
		(25 "Edge.Cuts" user "Board Geometry/Outline")
		(27 "Margin" user)
		(31 "F.CrtYd" user "Package Geometry/Place Bound Top")
		(29 "B.CrtYd" user "Package Geometry/Place Bound Bottom")
		(35 "F.Fab" user "Ref Des/Assembly Top")
		(33 "B.Fab" user "Ref Des/Assembly Bottom")
	)
	(footprint ""
		(layer "B.Cu")
		(at 137.414 -57.785 180)
		(property "Reference" "R243"
			(at 0.381 -1.18237 0)
			(unlocked yes)
			(layer "B.SilkS")
			(effects
				(font
					(size 0.7874 0.5842)
					(thickness 0.1524)
				)
				(justify mirror)
			)
		)
		(property "Value" "VAL*"
			(at -0.02032 2.13233 180)
			(unlocked yes)
			(layer "B.Fab")
			(hide yes)
			(effects
				(font
					(size 0.7874 0.5842)
					(thickness 0.1524)
				)
				(justify mirror)
			)
		)
		(property "Device Type" "RESISTOR-G155-14701-01,4.7KOHMA"
			(at -0.008382 1.210564 180)
			(unlocked yes)
			(layer "B.Fab")
			(hide yes)
			(effects
				(font
					(size 0.7874 0.5842)
					(thickness 0.1524)
				)
				(justify mirror)
			)
		)
		(property "User Part Number" "PARTNUM*"
			(at -0.02032 4.024884 180)
			(unlocked yes)
			(layer "Cmts.User")
			(hide yes)
			(effects
				(font
					(size 0.7874 0.5842)
					(thickness 0.1524)
				)
				(justify mirror)
			)
		)
		(property "Tolerance" "TOL*"
			(at -0.044704 3.05435 180)
			(unlocked yes)
			(layer "Cmts.User")
			(hide yes)
			(effects
				(font
					(size 0.7874 0.5842)
					(thickness 0.1524)
				)
				(justify mirror)
			)
		)
		(duplicate_pad_numbers_are_jumpers no)
		(fp_line
			(start 1.143 0.5588)
			(end -1.143 0.5588)
			(stroke
				(width 0.1)
				(type default)
			)
			(layer "B.SilkS")
		)
		(fp_line
			(start 1.143 -0.5588)
			(end 1.143 0.5588)
			(stroke
				(width 0.1)
				(type default)
			)
			(layer "B.SilkS")
		)
		(fp_line
			(start -1.143 0.5588)
			(end -1.143 -0.5588)
			(stroke
				(width 0.1)
				(type default)
			)
			(layer "B.SilkS")
		)
		(fp_line
			(start -1.143 -0.5588)
			(end 1.143 -0.5588)
			(stroke
				(width 0.1)
				(type default)
			)
			(layer "B.SilkS")
		)
		(fp_rect
			(start -1.143 -0.5588)
			(end 1.143 0.5588)
			(stroke
				(width 0)
				(type default)
			)
			(fill no)
			(layer "B.CrtYd")
		)
		(fp_line
			(start 0.508 0.3048)
			(end -0.508 0.3048)
			(stroke
				(width 0.1)
				(type default)
			)
			(layer "B.Fab")
		)
		(fp_line
			(start 0.508 -0.3048)
			(end 0.508 0.3048)
			(stroke
				(width 0.1)
				(type default)
			)
			(layer "B.Fab")
		)
		(fp_line
			(start -0.508 0.3048)
			(end -0.508 -0.3048)
			(stroke
				(width 0.1)
				(type default)
			)
			(layer "B.Fab")
		)
		(fp_line
			(start -0.508 -0.3048)
			(end 0.508 -0.3048)
			(stroke
				(width 0.1)
				(type default)
			)
			(layer "B.Fab")
		)
		(pad "1" smd rect
			(at 0.5334 0)
			(size 0.7112 0.6096)
			(layers "B.Cu" "B.Mask" "B.Paste")
			(net "XP3R3V")
		)
		(pad "2" smd rect
			(at -0.5334 0)
			(size 0.7112 0.6096)
			(layers "B.Cu" "B.Mask" "B.Paste")
			(net "XP1R0V_PG")
		)
		(zone
			(layer "B.Cu")
			(hatch none 0.5)
			(connect_pads
				(clearance 0)
			)
			(min_thickness 0.25)
			(keepout
				(tracks allowed)
				(vias not_allowed)
				(pads allowed)
				(copperpour not_allowed)
				(footprints allowed)
			)
			(placement
				(enabled no)
				(sheetname "")
			)
			(fill
				(thermal_gap 0.5)
				(thermal_bridge_width 0.5)
				(island_removal_mode 0)
			)
			(polygon
				(pts
					(xy 137.4902 -57.4802) (xy 137.4902 -58.0898) (xy 137.3378 -58.0898) (xy 137.3378 -57.4802)
				)
			)
		)
	)
	(footprint ""
		(layer "B.Cu")
		(at 139.954 -54.61 90)
		(property "Reference" "R250"
			(at 0.508 1.10363 270)
			(unlocked yes)
			(layer "B.SilkS")
			(effects
				(font
					(size 0.7874 0.5842)
					(thickness 0.1524)
				)
				(justify mirror)
			)
		)
		(property "Value" "VAL*"
			(at -0.02032 2.13233 90)
			(unlocked yes)
			(layer "B.Fab")
			(hide yes)
			(effects
				(font
					(size 0.7874 0.5842)
					(thickness 0.1524)
				)
				(justify mirror)
			)
		)
		(property "Tolerance" "TOL*"
			(at -0.044704 3.05435 90)
			(unlocked yes)
			(layer "Cmts.User")
			(hide yes)
			(effects
				(font
					(size 0.7874 0.5842)
					(thickness 0.1524)
				)
				(justify mirror)
			)
		)
		(property "User Part Number" "PARTNUM*"
			(at -0.02032 4.024884 90)
			(unlocked yes)
			(layer "Cmts.User")
			(hide yes)
			(effects
				(font
					(size 0.7874 0.5842)
					(thickness 0.1524)
				)
				(justify mirror)
			)
		)
		(property "Device Type" "RESISTOR-G155-100R0-J0,0OHM,-"
			(at -0.008382 1.210564 90)
			(unlocked yes)
			(layer "B.Fab")
			(hide yes)
			(effects
				(font
					(size 0.7874 0.5842)
					(thickness 0.1524)
				)
				(justify mirror)
			)
		)
		(duplicate_pad_numbers_are_jumpers no)
		(fp_line
			(start 1.143 -0.5588)
			(end 1.143 0.5588)
			(stroke
				(width 0.1)
				(type default)
			)
			(layer "B.SilkS")
		)
		(fp_line
			(start -1.143 -0.5588)
			(end 1.143 -0.5588)
			(stroke
				(width 0.1)
				(type default)
			)
			(layer "B.SilkS")
		)
		(fp_line
			(start 1.143 0.5588)
			(end -1.143 0.5588)
			(stroke
				(width 0.1)
				(type default)
			)
			(layer "B.SilkS")
		)
		(fp_line
			(start -1.143 0.5588)
			(end -1.143 -0.5588)
			(stroke
				(width 0.1)
				(type default)
			)
			(layer "B.SilkS")
		)
		(fp_poly
			(pts
				(xy 1.143 0.5588) (xy -1.143 0.5588) (xy -1.143 -0.5588) (xy 1.143 -0.5588)
			)
			(stroke
				(width 0)
				(type default)
			)
			(fill no)
			(layer "B.CrtYd")
		)
		(fp_line
			(start 0.508 -0.3048)
			(end 0.508 0.3048)
			(stroke
				(width 0.1)
				(type default)
			)
			(layer "B.Fab")
		)
		(fp_line
			(start -0.508 -0.3048)
			(end 0.508 -0.3048)
			(stroke
				(width 0.1)
				(type default)
			)
			(layer "B.Fab")
		)
		(fp_line
			(start 0.508 0.3048)
			(end -0.508 0.3048)
			(stroke
				(width 0.1)
				(type default)
			)
			(layer "B.Fab")
		)
		(fp_line
			(start -0.508 0.3048)
			(end -0.508 -0.3048)
			(stroke
				(width 0.1)
				(type default)
			)
			(layer "B.Fab")
		)
		(pad "1" smd rect
			(at 0.5334 0 270)
			(size 0.7112 0.6096)
			(layers "B.Cu" "B.Mask" "B.Paste")
			(net "XP1R0V_BT")
		)
		(pad "2" smd rect
			(at -0.5334 0 270)
			(size 0.7112 0.6096)
			(layers "B.Cu" "B.Mask" "B.Paste")
			(net "UNNAMED_523_CAPACITOR_I24_1")
		)
		(zone
			(layer "B.Cu")
			(hatch none 0.5)
			(connect_pads
				(clearance 0)
			)
			(min_thickness 0.25)
			(keepout
				(tracks allowed)
				(vias not_allowed)
				(pads allowed)
				(copperpour not_allowed)
				(footprints allowed)
			)
			(placement
				(enabled no)
				(sheetname "")
			)
			(fill
				(thermal_gap 0.5)
				(thermal_bridge_width 0.5)
				(island_removal_mode 0)
			)
			(polygon
				(pts
					(xy 140.2588 -54.6862) (xy 139.6492 -54.6862) (xy 139.6492 -54.5338) (xy 140.2588 -54.5338)
				)
			)
		)
		(zone
			(layer "B.Cu")
			(hatch none 0.5)
			(connect_pads
				(clearance 0)
			)
			(min_thickness 0.25)
			(keepout
				(tracks not_allowed)
				(vias allowed)
				(pads allowed)
				(copperpour not_allowed)
				(footprints allowed)
			)
			(placement
				(enabled no)
				(sheetname "")
			)
			(fill
				(thermal_gap 0.5)
				(thermal_bridge_width 0.5)
				(island_removal_mode 0)
			)
			(polygon
				(pts
					(xy 140.2588 -54.6862) (xy 139.6492 -54.6862) (xy 139.6492 -54.5338) (xy 140.2588 -54.5338)
				)
			)
		)
	)
	(footprint ""
		(layer "B.Cu")
		(at 117.346984 -32.822896 180)
		(property "Reference" "R275"
			(at -0.509016 -1.231646 0)
			(unlocked yes)
			(layer "B.SilkS")
			(effects
				(font
					(size 0.635 0.4064)
					(thickness 0.1524)
				)
				(justify mirror)
			)
		)
		(property "Value" "VAL*"
			(at 0 3.718306 180)
			(unlocked yes)
			(layer "B.Fab")
			(hide yes)
			(effects
				(font
					(size 0.7874 0.5842)
					(thickness 0.127)
				)
				(justify mirror)
			)
		)
		(property "Tolerance" "TOL*"
			(at 0 4.861306 180)
			(unlocked yes)
			(layer "Cmts.User")
			(hide yes)
			(effects
				(font
					(size 0.7874 0.5842)
					(thickness 0.127)
				)
				(justify mirror)
			)
		)
		(property "User Part Number" "PARTNUM*"
			(at 0 2.575306 180)
			(unlocked yes)
			(layer "Cmts.User")
			(hide yes)
			(effects
				(font
					(size 0.7874 0.5842)
					(thickness 0.127)
				)
				(justify mirror)
			)
		)
		(property "Device Type" "RESISTOR-G155-11000-01,100OHM,A"
			(at 0 1.432306 180)
			(unlocked yes)
			(layer "B.Fab")
			(hide yes)
			(effects
				(font
					(size 0.7874 0.5842)
					(thickness 0.127)
				)
				(justify mirror)
			)
		)
		(duplicate_pad_numbers_are_jumpers no)
		(fp_line
			(start 0.970026 0.4699)
			(end 0.970026 -0.4699)
			(stroke
				(width 0.1)
				(type default)
			)
			(layer "B.SilkS")
		)
		(fp_line
			(start 0.970026 -0.4699)
			(end -0.970026 -0.4699)
			(stroke
				(width 0.1)
				(type default)
			)
			(layer "B.SilkS")
		)
		(fp_line
			(start -0.970026 0.4699)
			(end 0.970026 0.4699)
			(stroke
				(width 0.1)
				(type default)
			)
			(layer "B.SilkS")
		)
		(fp_line
			(start -0.970026 -0.4699)
			(end -0.970026 0.4699)
			(stroke
				(width 0.1)
				(type default)
			)
			(layer "B.SilkS")
		)
		(fp_poly
			(pts
				(xy 0.970026 0.4699) (xy -0.970026 0.4699) (xy -0.970026 -0.4699) (xy 0.970026 -0.4699)
			)
			(stroke
				(width 0)
				(type default)
			)
			(fill no)
			(layer "B.CrtYd")
		)
		(fp_line
			(start 0.508 0.3048)
			(end 0.508 -0.3048)
			(stroke
				(width 0.1)
				(type default)
			)
			(layer "B.Fab")
		)
		(fp_line
			(start 0.508 -0.3048)
			(end -0.508 -0.3048)
			(stroke
				(width 0.1)
				(type default)
			)
			(layer "B.Fab")
		)
		(fp_line
			(start -0.508 0.3048)
			(end 0.508 0.3048)
			(stroke
				(width 0.1)
				(type default)
			)
			(layer "B.Fab")
		)
		(fp_line
			(start -0.508 -0.3048)
			(end -0.508 0.3048)
			(stroke
				(width 0.1)
				(type default)
			)
			(layer "B.Fab")
		)
		(pad "1" smd circle
			(at 0.500126 0)
			(size 0.635 0.635)
			(layers "B.Cu" "B.Mask" "B.Paste")
			(net "FPGA_IN_MAC_PPS_OUTP")
		)
		(pad "2" smd circle
			(at -0.500126 0)
			(size 0.635 0.635)
			(layers "B.Cu" "B.Mask" "B.Paste")
			(net "FPGA_IN_MAC_PPS_OUTN")
		)
	)
	(footprint ""
		(layer "B.Cu")
		(at 140.335 -77.851)
		(property "Reference" "R41"
			(at 0.381 -2.11963 0)
			(unlocked yes)
			(layer "B.SilkS")
			(effects
				(font
					(size 0.7874 0.5842)
					(thickness 0.1524)
				)
				(justify mirror)
			)
		)
		(property "Value" "VAL*"
			(at -0.02032 2.13233 0)
			(unlocked yes)
			(layer "B.Fab")
			(hide yes)
			(effects
				(font
					(size 0.7874 0.5842)
					(thickness 0.1524)
				)
				(justify mirror)
			)
		)
		(property "Tolerance" "TOL*"
			(at -0.044704 3.05435 0)
			(unlocked yes)
			(layer "Cmts.User")
			(hide yes)
			(effects
				(font
					(size 0.7874 0.5842)
					(thickness 0.1524)
				)
				(justify mirror)
			)
		)
		(property "User Part Number" "PARTNUM*"
			(at -0.02032 4.024884 0)
			(unlocked yes)
			(layer "Cmts.User")
			(hide yes)
			(effects
				(font
					(size 0.7874 0.5842)
					(thickness 0.1524)
				)
				(justify mirror)
			)
		)
		(property "Device Type" "RESISTOR-G155-100R0-J0,0OHM,-"
			(at -0.008382 1.210564 0)
			(unlocked yes)
			(layer "B.Fab")
			(hide yes)
			(effects
				(font
					(size 0.7874 0.5842)
					(thickness 0.1524)
				)
				(justify mirror)
			)
		)
		(duplicate_pad_numbers_are_jumpers no)
		(fp_line
			(start -1.143 -0.5588)
			(end 1.143 -0.5588)
			(stroke
				(width 0.1)
				(type default)
			)
			(layer "B.SilkS")
		)
		(fp_line
			(start -1.143 0.5588)
			(end -1.143 -0.5588)
			(stroke
				(width 0.1)
				(type default)
			)
			(layer "B.SilkS")
		)
		(fp_line
			(start 1.143 -0.5588)
			(end 1.143 0.5588)
			(stroke
				(width 0.1)
				(type default)
			)
			(layer "B.SilkS")
		)
		(fp_line
			(start 1.143 0.5588)
			(end -1.143 0.5588)
			(stroke
				(width 0.1)
				(type default)
			)
			(layer "B.SilkS")
		)
		(fp_rect
			(start 1.143 0.5588)
			(end -1.143 -0.5588)
			(stroke
				(width 0)
				(type default)
			)
			(fill no)
			(layer "B.CrtYd")
		)
		(fp_line
			(start -0.508 -0.3048)
			(end 0.508 -0.3048)
			(stroke
				(width 0.1)
				(type default)
			)
			(layer "B.Fab")
		)
		(fp_line
			(start -0.508 0.3048)
			(end -0.508 -0.3048)
			(stroke
				(width 0.1)
				(type default)
			)
			(layer "B.Fab")
		)
		(fp_line
			(start 0.508 -0.3048)
			(end 0.508 0.3048)
			(stroke
				(width 0.1)
				(type default)
			)
			(layer "B.Fab")
		)
		(fp_line
			(start 0.508 0.3048)
			(end -0.508 0.3048)
			(stroke
				(width 0.1)
				(type default)
			)
			(layer "B.Fab")
		)
		(pad "1" smd rect
			(at 0.5334 0 180)
			(size 0.7112 0.6096)
			(layers "B.Cu" "B.Mask" "B.Paste")
			(net "PCIE_CONN_TDI")
		)
		(pad "2" smd rect
			(at -0.5334 0 180)
			(size 0.7112 0.6096)
			(layers "B.Cu" "B.Mask" "B.Paste")
			(net "FPGA_TDI")
		)
		(zone
			(layer "B.Cu")
			(hatch none 0.5)
			(connect_pads
				(clearance 0)
			)
			(min_thickness 0.25)
			(keepout
				(tracks allowed)
				(vias not_allowed)
				(pads allowed)
				(copperpour not_allowed)
				(footprints allowed)
			)
			(placement
				(enabled no)
				(sheetname "")
			)
			(fill
				(thermal_gap 0.5)
				(thermal_bridge_width 0.5)
				(island_removal_mode 0)
			)
			(polygon
				(pts
					(xy 140.4112 -77.5462) (xy 140.4112 -78.1558) (xy 140.2588 -78.1558) (xy 140.2588 -77.5462)
				)
			)
		)
	)
	(footprint ""
		(layer "B.Cu")
		(at 62.514988 -15.367 -90)
		(property "Reference" "C24"
			(at 2.032 0.062738 270)
			(unlocked yes)
			(layer "B.SilkS")
			(effects
				(font
					(size 0.635 0.4064)
					(thickness 0.1524)
				)
				(justify mirror)
			)
		)
		(property "Value" "VAL*"
			(at -0.0762 2.067306 270)
			(unlocked yes)
			(layer "B.Fab")
			(hide yes)
			(effects
				(font
					(size 0.7874 0.5842)
					(thickness 0.1524)
				)
				(justify mirror)
			)
		)
		(property "Tolerance" "TOL*"
			(at -0.0762 3.032506 270)
			(unlocked yes)
			(layer "Cmts.User")
			(hide yes)
			(effects
				(font
					(size 0.7874 0.5842)
					(thickness 0.1524)
				)
				(justify mirror)
			)
		)
		(property "User Part Number" "PARTNUM*"
			(at -0.1016 4.023106 270)
			(unlocked yes)
			(layer "Cmts.User")
			(hide yes)
			(effects
				(font
					(size 0.7874 0.5842)
					(thickness 0.1524)
				)
				(justify mirror)
			)
		)
		(property "Device Type" "CAPACITOR-G105-0B104-CK,0.1UF,A"
			(at -0.0508 1.127506 270)
			(unlocked yes)
			(layer "B.Fab")
			(hide yes)
			(effects
				(font
					(size 0.7874 0.5842)
					(thickness 0.1524)
				)
				(justify mirror)
			)
		)
		(duplicate_pad_numbers_are_jumpers no)
		(fp_line
			(start -1.143 0.5588)
			(end -1.143 -0.5588)
			(stroke
				(width 0.1)
				(type default)
			)
			(layer "B.SilkS")
		)
		(fp_line
			(start 1.143 0.5588)
			(end -1.143 0.5588)
			(stroke
				(width 0.1)
				(type default)
			)
			(layer "B.SilkS")
		)
		(fp_line
			(start -1.143 -0.5588)
			(end 1.143 -0.5588)
			(stroke
				(width 0.1)
				(type default)
			)
			(layer "B.SilkS")
		)
		(fp_line
			(start 1.143 -0.5588)
			(end 1.143 0.5588)
			(stroke
				(width 0.1)
				(type default)
			)
			(layer "B.SilkS")
		)
		(fp_rect
			(start 1.143 0.5588)
			(end -1.143 -0.5588)
			(stroke
				(width 0)
				(type default)
			)
			(fill no)
			(layer "B.CrtYd")
		)
		(fp_line
			(start -0.508 0.3048)
			(end -0.508 -0.3048)
			(stroke
				(width 0.1)
				(type default)
			)
			(layer "B.Fab")
		)
		(fp_line
			(start 0.508 0.3048)
			(end -0.508 0.3048)
			(stroke
				(width 0.1)
				(type default)
			)
			(layer "B.Fab")
		)
		(fp_line
			(start -0.508 -0.3048)
			(end 0.508 -0.3048)
			(stroke
				(width 0.1)
				(type default)
			)
			(layer "B.Fab")
		)
		(fp_line
			(start 0.508 -0.3048)
			(end 0.508 0.3048)
			(stroke
				(width 0.1)
				(type default)
			)
			(layer "B.Fab")
		)
		(pad "1" smd rect
			(at 0.5334 0 90)
			(size 0.7112 0.6096)
			(layers "B.Cu" "B.Mask" "B.Paste")
			(net "C_CPU_RX_PCIE_MGT0_TXP")
		)
		(pad "2" smd rect
			(at -0.5334 0 90)
			(size 0.7112 0.6096)
			(layers "B.Cu" "B.Mask" "B.Paste")
			(net "CPU_RX_PCIE_MGT0_TXP")
		)
		(zone
			(layer "B.Cu")
			(hatch none 0.5)
			(connect_pads
				(clearance 0)
			)
			(min_thickness 0.25)
			(keepout
				(tracks allowed)
				(vias not_allowed)
				(pads allowed)
				(copperpour not_allowed)
				(footprints allowed)
			)
			(placement
				(enabled no)
				(sheetname "")
			)
			(fill
				(thermal_gap 0.5)
				(thermal_bridge_width 0.5)
				(island_removal_mode 0)
			)
			(polygon
				(pts
					(xy 62.210188 -15.2908) (xy 62.819788 -15.2908) (xy 62.819788 -15.4432) (xy 62.210188 -15.4432)
				)
			)
		)
	)
)
